# SCM (Grand Teton) — schematic netlist excerpt (pin names and nets, part order shuffled) for the footprints in the layout excerpt that follows; sources: Cadence DE-HDL packaged netlist, KiCad conversion of 12092022_DA0F0TMDCD0_F0T_Management_Board_D_brd_V3_OCP.brd

J20  PICOPROBE_BXA  DELTA-L 4.0 EMPTY  pkg TRIANG_LAUNCH_3PXB  page 58
  \1_p\  = 85_5INCH_BOT_DP
  \2_n\  = 85_5INCH_BOT_DN
  \3_g\  = GND_P1

(kicad_pcb
	(version 20260206)
	(generator "pcbnew")
	(generator_version "10.0")
	(general
		(thickness 1.6)
		(legacy_teardrops no)
	)
	(paper "A4")
	(title_block
		(title "12092022_DA0F0TMDCD0_F0T_Management_Board_D_brd_V3_OCP.brd")
		(comment 1 "Grand Teton / footprints 808-808 of 1440")
	)
	(layers
		(0 "F.Cu" signal "TOP")
		(4 "In1.Cu" signal "GND")
		(6 "In2.Cu" signal "IN1")
		(8 "In3.Cu" signal "GND1")
		(10 "In4.Cu" signal "IN2")
		(12 "In5.Cu" signal "VCC")
		(14 "In6.Cu" signal "VCC1")
		(16 "In7.Cu" signal "IN3")
		(18 "In8.Cu" signal "GND2")
		(20 "In9.Cu" signal "IN4")
		(22 "In10.Cu" signal "GND3")
		(2 "B.Cu" signal "BOTTOM")
		(9 "F.Adhes" user "F.Adhesive")
		(11 "B.Adhes" user "B.Adhesive")
		(13 "F.Paste" user "Package Geometry/Pastemask Top")
		(15 "B.Paste" user "Package Geometry/Pastemask Bottom")
		(5 "F.SilkS" user "Ref Des/Silkscreen Top")
		(7 "B.SilkS" user "Ref Des/Silkscreen Bottom")
		(1 "F.Mask" user "Board Geometry/Soldermask Top")
		(3 "B.Mask" user "Board Geometry/Soldermask Bottom")
		(17 "Dwgs.User" user "User.Drawings")
		(19 "Cmts.User" user "User.Comments")
		(21 "Eco1.User" user "User.Eco1")
		(23 "Eco2.User" user "User.Eco2")
		(25 "Edge.Cuts" user "Board Geometry/Outline")
		(27 "Margin" user)
		(31 "F.CrtYd" user "Package Geometry/Place Bound Top")
		(29 "B.CrtYd" user "Package Geometry/Place Bound Bottom")
		(35 "F.Fab" user "Ref Des/Assembly Top")
		(33 "B.Fab" user "Ref Des/Assembly Bottom")
	)
	(footprint ""
		(layer "B.Cu")
		(at 103.8225 -65.6336 -90)
		(property "Reference" "J20"
			(at 0.8636 -2.95783 270)
			(unlocked yes)
			(layer "B.SilkS")
			(effects
				(font
					(size 0.7874 0.5842)
					(thickness 0.1524)
				)
				(justify left mirror)
			)
		)
		(property "Value" ""
			(at 0 0 90)
			(layer "B.Fab")
			(effects
				(font
					(size 1.27 1.27)
				)
				(justify mirror)
			)
		)
		(duplicate_pad_numbers_are_jumpers no)
		(fp_line
			(start -1.2192 2.1082)
			(end 1.2192 2.1082)
			(stroke
				(width 0.1524)
				(type default)
			)
			(layer "B.SilkS")
		)
		(fp_line
			(start 1.2192 2.1082)
			(end 1.2192 -2.1082)
			(stroke
				(width 0.1524)
				(type default)
			)
			(layer "B.SilkS")
		)
		(fp_line
			(start -1.2192 0.450088)
			(end -1.2192 2.1082)
			(stroke
				(width 0.1524)
				(type default)
			)
			(layer "B.SilkS")
		)
		(fp_line
			(start -1.2192 -2.1082)
			(end -1.2192 -0.466344)
			(stroke
				(width 0.1524)
				(type default)
			)
			(layer "B.SilkS")
		)
		(fp_line
			(start 1.2192 -2.1082)
			(end -1.2192 -2.1082)
			(stroke
				(width 0.1524)
				(type default)
			)
			(layer "B.SilkS")
		)
		(pad "" np_thru_hole circle
			(at -3.4671 -1.27 180)
			(size 1.0414 1.0414)
			(drill 1.0414)
			(layers "*.Cu" "*.Mask")
			(clearance 0.381)
			(thermal_gap 0.381)
		)
		(pad "" np_thru_hole circle
			(at -3.4671 1.27 180)
			(size 1.0414 1.0414)
			(drill 1.0414)
			(layers "*.Cu" "*.Mask")
			(clearance 0.381)
			(thermal_gap 0.381)
		)
		(pad "" np_thru_hole circle
			(at 2.8829 -1.27 180)
			(size 1.0414 1.0414)
			(drill 1.0414)
			(layers "*.Cu" "*.Mask")
			(clearance 0.381)
			(thermal_gap 0.381)
		)
		(pad "" np_thru_hole circle
			(at 2.8829 1.27 180)
			(size 1.0414 1.0414)
			(drill 1.0414)
			(layers "*.Cu" "*.Mask")
			(clearance 0.381)
			(thermal_gap 0.381)
		)
		(pad "1" smd rect
			(at -0.8255 -0.249936 180)
			(size 0.3048 0.508)
			(layers "B.Cu" "B.Mask" "B.Paste")
			(net "85_5INCH_BOT_DP")
		)
		(pad "2" smd rect
			(at -0.8255 0.249936 180)
			(size 0.3048 0.508)
			(layers "B.Cu" "B.Mask" "B.Paste")
			(net "85_5INCH_BOT_DN")
		)
		(pad "3" smd circle
			(at 0 0 90)
			(size 0 0)
			(layers "B.Cu" "B.Mask" "B.Paste")
			(net "GND_P1")
		)
		(zone
			(layers "F.Cu" "B.Cu" "In1.Cu" "In2.Cu" "In3.Cu" "In4.Cu" "In5.Cu" "In6.Cu"
				"In7.Cu" "In8.Cu" "In9.Cu" "In10.Cu"
			)
			(hatch none 0.5)
			(connect_pads
				(clearance 0)
			)
			(min_thickness 0.25)
			(keepout
				(tracks not_allowed)
				(vias allowed)
				(pads allowed)
				(copperpour not_allowed)
				(footprints allowed)
			)
			(placement
				(enabled no)
				(sheetname "")
			)
			(fill
				(thermal_gap 0.5)
				(thermal_bridge_width 0.5)
				(island_removal_mode 0)
			)
			(polygon
				(pts
					(arc
						(start 103.4796 -69.1007)
						(mid 101.6254 -69.1007)
						(end 103.4796 -69.1007)
					)
				)
			)
		)
		(zone
			(layers "F.Cu" "B.Cu" "In1.Cu" "In2.Cu" "In3.Cu" "In4.Cu" "In5.Cu" "In6.Cu"
				"In7.Cu" "In8.Cu" "In9.Cu" "In10.Cu"
			)
			(hatch none 0.5)
			(connect_pads
				(clearance 0)
			)
			(min_thickness 0.25)
			(keepout
				(tracks not_allowed)
				(vias allowed)
				(pads allowed)
				(copperpour not_allowed)
				(footprints allowed)
			)
			(placement
				(enabled no)
				(sheetname "")
			)
			(fill
				(thermal_gap 0.5)
				(thermal_bridge_width 0.5)
				(island_removal_mode 0)
			)
			(polygon
				(pts
					(arc
						(start 103.4796 -62.7507)
						(mid 101.6254 -62.7507)
						(end 103.4796 -62.7507)
					)
				)
			)
		)
		(zone
			(layers "F.Cu" "B.Cu" "In1.Cu" "In2.Cu" "In3.Cu" "In4.Cu" "In5.Cu" "In6.Cu"
				"In7.Cu" "In8.Cu" "In9.Cu" "In10.Cu"
			)
			(hatch none 0.5)
			(connect_pads
				(clearance 0)
			)
			(min_thickness 0.25)
			(keepout
				(tracks not_allowed)
				(vias allowed)
				(pads allowed)
				(copperpour not_allowed)
				(footprints allowed)
			)
			(placement
				(enabled no)
				(sheetname "")
			)
			(fill
				(thermal_gap 0.5)
				(thermal_bridge_width 0.5)
				(island_removal_mode 0)
			)
			(polygon
				(pts
					(arc
						(start 106.0196 -69.1007)
						(mid 104.1654 -69.1007)
						(end 106.0196 -69.1007)
					)
				)
			)
		)
		(zone
			(layers "F.Cu" "B.Cu" "In1.Cu" "In2.Cu" "In3.Cu" "In4.Cu" "In5.Cu" "In6.Cu"
				"In7.Cu" "In8.Cu" "In9.Cu" "In10.Cu"
			)
			(hatch none 0.5)
			(connect_pads
				(clearance 0)
			)
			(min_thickness 0.25)
			(keepout
				(tracks not_allowed)
				(vias allowed)
				(pads allowed)
				(copperpour not_allowed)
				(footprints allowed)
			)
			(placement
				(enabled no)
				(sheetname "")
			)
			(fill
				(thermal_gap 0.5)
				(thermal_bridge_width 0.5)
				(island_removal_mode 0)
			)
			(polygon
				(pts
					(arc
						(start 106.0196 -62.7507)
						(mid 104.1654 -62.7507)
						(end 106.0196 -62.7507)
					)
				)
			)
		)
		(zone
			(layer "B.Cu")
			(hatch none 0.5)
			(connect_pads
				(clearance 0)
			)
			(min_thickness 0.25)
			(keepout
				(tracks not_allowed)
				(vias allowed)
				(pads allowed)
				(copperpour not_allowed)
				(footprints allowed)
			)
			(placement
				(enabled no)
				(sheetname "")
			)
			(fill
				(thermal_gap 0.5)
				(thermal_bridge_width 0.5)
				(island_removal_mode 0)
			)
			(polygon
				(pts
					(xy 104.37114 -66.7512) (xy 104.275636 -66.7512) (xy 104.275636 -66.1543) (xy 103.869236 -66.1543)
					(xy 103.869236 -66.7512) (xy 103.775764 -66.7512) (xy 103.775764 -66.1543) (xy 103.369364 -66.1543)
					(xy 103.369364 -66.7512) (xy 103.27386 -66.7512) (xy 103.27386 -66.0527) (xy 104.37114 -66.0527)
				)
			)
		)
	)
)
